(kicad_pcb
	(version 20260206)
	(generator "pcbnew")
	(generator_version "10.0")
	(general
		(thickness 1.6)
		(legacy_teardrops no)
	)
	(paper "A4")
	(title_block
		(title "01162023_DA0F0TEBIF0_F0T_Expander_BD_F_brd_V02_OCP.brd")
		(comment 1 "Grand Teton / footprints 7548-7556 of 9728")
	)
	(layers
		(0 "F.Cu" signal "TOP")
		(4 "In1.Cu" signal "GND")
		(6 "In2.Cu" signal "VCC")
		(8 "In3.Cu" signal "VCC1")
		(10 "In4.Cu" signal "GND1")
		(12 "In5.Cu" signal "IN1")
		(14 "In6.Cu" signal "GND2")
		(16 "In7.Cu" signal "IN2")
		(18 "In8.Cu" signal "GND3")
		(20 "In9.Cu" signal "IN3")
		(22 "In10.Cu" signal "GND4")
		(24 "In11.Cu" signal "IN4")
		(26 "In12.Cu" signal "GND5")
		(28 "In13.Cu" signal "IN5")
		(30 "In14.Cu" signal "GND6")
		(32 "In15.Cu" signal "IN6")
		(34 "In16.Cu" signal "GND7")
		(2 "B.Cu" signal "BOTTOM")
		(9 "F.Adhes" user "F.Adhesive")
		(11 "B.Adhes" user "B.Adhesive")
		(13 "F.Paste" user "Package Geometry/Pastemask Top")
		(15 "B.Paste" user "Package Geometry/Pastemask Bottom")
		(5 "F.SilkS" user "Ref Des/Silkscreen Top")
		(7 "B.SilkS" user "Ref Des/Silkscreen Bottom")
		(1 "F.Mask" user "Board Geometry/Soldermask Top")
		(3 "B.Mask" user "Board Geometry/Soldermask Bottom")
		(17 "Dwgs.User" user "User.Drawings")
		(19 "Cmts.User" user "User.Comments")
		(21 "Eco1.User" user "User.Eco1")
		(23 "Eco2.User" user "User.Eco2")
		(25 "Edge.Cuts" user "Board Geometry/Outline")
		(27 "Margin" user)
		(31 "F.CrtYd" user "Package Geometry/Place Bound Top")
		(29 "B.CrtYd" user "Package Geometry/Place Bound Bottom")
		(35 "F.Fab" user "Ref Des/Assembly Top")
		(33 "B.Fab" user "Ref Des/Assembly Bottom")
	)
	(footprint ""
		(layer "B.Cu")
		(at 298.976542 -293.99992 90)
		(property "Reference" "C1673"
			(at 0 0 90)
			(layer "B.SilkS")
			(hide yes)
			(effects
				(font
					(size 1.27 1.27)
				)
				(justify mirror)
			)
		)
		(property "Value" ""
			(at 0 0 90)
			(layer "B.Fab")
			(effects
				(font
					(size 1.27 1.27)
				)
				(justify mirror)
			)
		)
		(duplicate_pad_numbers_are_jumpers no)
		(fp_line
			(start 0.299974 -0.150114)
			(end -0.299974 -0.150114)
			(stroke
				(width 0.1)
				(type default)
			)
			(layer "B.Fab")
		)
		(fp_line
			(start -0.299974 -0.150114)
			(end -0.299974 0.150114)
			(stroke
				(width 0.1)
				(type default)
			)
			(layer "B.Fab")
		)
		(fp_line
			(start 0.299974 0.150114)
			(end 0.299974 -0.150114)
			(stroke
				(width 0.1)
				(type default)
			)
			(layer "B.Fab")
		)
		(fp_line
			(start -0.299974 0.150114)
			(end 0.299974 0.150114)
			(stroke
				(width 0.1)
				(type default)
			)
			(layer "B.Fab")
		)
		(pad "1" smd rect
			(at 0.2667 0 270)
			(size 0.3048 0.381)
			(layers "B.Cu" "B.Mask" "B.Paste")
			(net "P0V8_SERDES_VDDA_PEX2")
		)
		(pad "2" smd rect
			(at -0.2667 0 270)
			(size 0.3048 0.381)
			(layers "B.Cu" "B.Mask" "B.Paste")
			(net "GND")
		)
	)
	(footprint ""
		(layer "B.Cu")
		(at 407.949908 -288.299906 90)
		(property "Reference" "C3453"
			(at 0 0 90)
			(layer "B.SilkS")
			(hide yes)
			(effects
				(font
					(size 1.27 1.27)
				)
				(justify mirror)
			)
		)
		(property "Value" ""
			(at 0 0 90)
			(layer "B.Fab")
			(effects
				(font
					(size 1.27 1.27)
				)
				(justify mirror)
			)
		)
		(duplicate_pad_numbers_are_jumpers no)
		(fp_line
			(start 0.299974 -0.150114)
			(end -0.299974 -0.150114)
			(stroke
				(width 0.1)
				(type default)
			)
			(layer "B.Fab")
		)
		(fp_line
			(start -0.299974 -0.150114)
			(end -0.299974 0.150114)
			(stroke
				(width 0.1)
				(type default)
			)
			(layer "B.Fab")
		)
		(fp_line
			(start 0.299974 0.150114)
			(end 0.299974 -0.150114)
			(stroke
				(width 0.1)
				(type default)
			)
			(layer "B.Fab")
		)
		(fp_line
			(start -0.299974 0.150114)
			(end 0.299974 0.150114)
			(stroke
				(width 0.1)
				(type default)
			)
			(layer "B.Fab")
		)
		(pad "1" smd rect
			(at 0.2667 0 270)
			(size 0.3048 0.381)
			(layers "B.Cu" "B.Mask" "B.Paste")
			(net "P1V25_PEX3")
		)
		(pad "2" smd rect
			(at -0.2667 0 270)
			(size 0.3048 0.381)
			(layers "B.Cu" "B.Mask" "B.Paste")
			(net "GND")
		)
	)
	(footprint ""
		(layer "B.Cu")
		(at 49.1998 -288.774886 180)
		(property "Reference" "C3010"
			(at 0 0 0)
			(layer "B.SilkS")
			(hide yes)
			(effects
				(font
					(size 1.27 1.27)
				)
				(justify mirror)
			)
		)
		(property "Value" ""
			(at 0 0 0)
			(layer "B.Fab")
			(effects
				(font
					(size 1.27 1.27)
				)
				(justify mirror)
			)
		)
		(duplicate_pad_numbers_are_jumpers no)
		(fp_line
			(start 0.299974 0.150114)
			(end 0.299974 -0.150114)
			(stroke
				(width 0.1)
				(type default)
			)
			(layer "B.Fab")
		)
		(fp_line
			(start 0.299974 -0.150114)
			(end -0.299974 -0.150114)
			(stroke
				(width 0.1)
				(type default)
			)
			(layer "B.Fab")
		)
		(fp_line
			(start -0.299974 0.150114)
			(end 0.299974 0.150114)
			(stroke
				(width 0.1)
				(type default)
			)
			(layer "B.Fab")
		)
		(fp_line
			(start -0.299974 -0.150114)
			(end -0.299974 0.150114)
			(stroke
				(width 0.1)
				(type default)
			)
			(layer "B.Fab")
		)
		(pad "1" smd rect
			(at 0.2667 0)
			(size 0.3048 0.381)
			(layers "B.Cu" "B.Mask" "B.Paste")
			(net "P1V8_VDDA_PEX0")
		)
		(pad "2" smd rect
			(at -0.2667 0)
			(size 0.3048 0.381)
			(layers "B.Cu" "B.Mask" "B.Paste")
			(net "GND")
		)
	)
	(footprint ""
		(layer "B.Cu")
		(at 42.963846 -285.853632)
		(property "Reference" "C2990"
			(at 0 0 0)
			(layer "B.SilkS")
			(hide yes)
			(effects
				(font
					(size 1.27 1.27)
				)
				(justify mirror)
			)
		)
		(property "Value" ""
			(at 0 0 0)
			(layer "B.Fab")
			(effects
				(font
					(size 1.27 1.27)
				)
				(justify mirror)
			)
		)
		(duplicate_pad_numbers_are_jumpers no)
		(fp_line
			(start -1.2954 -0.5842)
			(end -1.2954 0.5842)
			(stroke
				(width 0.1524)
				(type default)
			)
			(layer "B.SilkS")
		)
		(fp_line
			(start -1.2954 0.5842)
			(end 1.2954 0.5842)
			(stroke
				(width 0.1524)
				(type default)
			)
			(layer "B.SilkS")
		)
		(fp_line
			(start 1.2954 -0.5842)
			(end -1.2954 -0.5842)
			(stroke
				(width 0.1524)
				(type default)
			)
			(layer "B.SilkS")
		)
		(fp_line
			(start 1.2954 0.5842)
			(end 1.2954 -0.5842)
			(stroke
				(width 0.1524)
				(type default)
			)
			(layer "B.SilkS")
		)
		(fp_line
			(start -1.1938 -0.4064)
			(end -1.1938 0.4064)
			(stroke
				(width 0.1)
				(type default)
			)
			(layer "B.Fab")
		)
		(fp_line
			(start -1.1938 0.4064)
			(end -0.8636 0.4064)
			(stroke
				(width 0.1)
				(type default)
			)
			(layer "B.Fab")
		)
		(fp_line
			(start -0.8636 -0.4572)
			(end -0.8636 -0.4064)
			(stroke
				(width 0.1)
				(type default)
			)
			(layer "B.Fab")
		)
		(fp_line
			(start -0.8636 -0.4064)
			(end -1.1938 -0.4064)
			(stroke
				(width 0.1)
				(type default)
			)
			(layer "B.Fab")
		)
		(fp_line
			(start -0.8636 0.4064)
			(end -0.8636 0.4572)
			(stroke
				(width 0.1)
				(type default)
			)
			(layer "B.Fab")
		)
		(fp_line
			(start -0.8636 0.4572)
			(end 0.8636 0.4572)
			(stroke
				(width 0.1)
				(type default)
			)
			(layer "B.Fab")
		)
		(fp_line
			(start 0.8636 -0.4572)
			(end -0.8636 -0.4572)
			(stroke
				(width 0.1)
				(type default)
			)
			(layer "B.Fab")
		)
		(fp_line
			(start 0.8636 -0.4064)
			(end 0.8636 -0.4572)
			(stroke
				(width 0.1)
				(type default)
			)
			(layer "B.Fab")
		)
		(fp_line
			(start 0.8636 0.4064)
			(end 1.1938 0.4064)
			(stroke
				(width 0.1)
				(type default)
			)
			(layer "B.Fab")
		)
		(fp_line
			(start 0.8636 0.4572)
			(end 0.8636 0.4064)
			(stroke
				(width 0.1)
				(type default)
			)
			(layer "B.Fab")
		)
		(fp_line
			(start 1.1938 -0.4064)
			(end 0.8636 -0.4064)
			(stroke
				(width 0.1)
				(type default)
			)
			(layer "B.Fab")
		)
		(fp_line
			(start 1.1938 0.4064)
			(end 1.1938 -0.4064)
			(stroke
				(width 0.1)
				(type default)
			)
			(layer "B.Fab")
		)
		(pad "1" smd rect
			(at 0.7366 0 270)
			(size 0.7112 0.8128)
			(layers "B.Cu" "B.Mask" "B.Paste")
			(net "P1V8_PEX")
		)
		(pad "2" smd rect
			(at -0.7366 0 270)
			(size 0.7112 0.8128)
			(layers "B.Cu" "B.Mask" "B.Paste")
			(net "GND")
		)
	)
	(footprint ""
		(layer "B.Cu")
		(at 217.659458 -278.05761)
		(property "Reference" "C4291"
			(at 0 0 0)
			(layer "B.SilkS")
			(hide yes)
			(effects
				(font
					(size 1.27 1.27)
				)
				(justify mirror)
			)
		)
		(property "Value" ""
			(at 0 0 0)
			(layer "B.Fab")
			(effects
				(font
					(size 1.27 1.27)
				)
				(justify mirror)
			)
		)
		(duplicate_pad_numbers_are_jumpers no)
		(fp_line
			(start -1.2954 -0.5842)
			(end -1.2954 0.5842)
			(stroke
				(width 0.1524)
				(type default)
			)
			(layer "B.SilkS")
		)
		(fp_line
			(start -1.2954 0.5842)
			(end 1.2954 0.5842)
			(stroke
				(width 0.1524)
				(type default)
			)
			(layer "B.SilkS")
		)
		(fp_line
			(start 1.2954 -0.5842)
			(end -1.2954 -0.5842)
			(stroke
				(width 0.1524)
				(type default)
			)
			(layer "B.SilkS")
		)
		(fp_line
			(start 1.2954 0.5842)
			(end 1.2954 -0.5842)
			(stroke
				(width 0.1524)
				(type default)
			)
			(layer "B.SilkS")
		)
		(fp_line
			(start -1.1938 -0.4064)
			(end -1.1938 0.4064)
			(stroke
				(width 0.1)
				(type default)
			)
			(layer "B.Fab")
		)
		(fp_line
			(start -1.1938 0.4064)
			(end -0.8636 0.4064)
			(stroke
				(width 0.1)
				(type default)
			)
			(layer "B.Fab")
		)
		(fp_line
			(start -0.8636 -0.4572)
			(end -0.8636 -0.4064)
			(stroke
				(width 0.1)
				(type default)
			)
			(layer "B.Fab")
		)
		(fp_line
			(start -0.8636 -0.4064)
			(end -1.1938 -0.4064)
			(stroke
				(width 0.1)
				(type default)
			)
			(layer "B.Fab")
		)
		(fp_line
			(start -0.8636 0.4064)
			(end -0.8636 0.4572)
			(stroke
				(width 0.1)
				(type default)
			)
			(layer "B.Fab")
		)
		(fp_line
			(start -0.8636 0.4572)
			(end 0.8636 0.4572)
			(stroke
				(width 0.1)
				(type default)
			)
			(layer "B.Fab")
		)
		(fp_line
			(start 0.8636 -0.4572)
			(end -0.8636 -0.4572)
			(stroke
				(width 0.1)
				(type default)
			)
			(layer "B.Fab")
		)
		(fp_line
			(start 0.8636 -0.4064)
			(end 0.8636 -0.4572)
			(stroke
				(width 0.1)
				(type default)
			)
			(layer "B.Fab")
		)
		(fp_line
			(start 0.8636 0.4064)
			(end 1.1938 0.4064)
			(stroke
				(width 0.1)
				(type default)
			)
			(layer "B.Fab")
		)
		(fp_line
			(start 0.8636 0.4572)
			(end 0.8636 0.4064)
			(stroke
				(width 0.1)
				(type default)
			)
			(layer "B.Fab")
		)
		(fp_line
			(start 1.1938 -0.4064)
			(end 0.8636 -0.4064)
			(stroke
				(width 0.1)
				(type default)
			)
			(layer "B.Fab")
		)
		(fp_line
			(start 1.1938 0.4064)
			(end 1.1938 -0.4064)
			(stroke
				(width 0.1)
				(type default)
			)
			(layer "B.Fab")
		)
		(pad "1" smd rect
			(at 0.7366 0 270)
			(size 0.7112 0.8128)
			(layers "B.Cu" "B.Mask" "B.Paste")
			(net "P1V25_PEX1")
		)
		(pad "2" smd rect
			(at -0.7366 0 270)
			(size 0.7112 0.8128)
			(layers "B.Cu" "B.Mask" "B.Paste")
			(net "GND")
		)
	)
	(footprint ""
		(layer "B.Cu")
		(at 177.42027 -199.303386)
		(property "Reference" "R1033"
			(at 0 0 0)
			(layer "B.SilkS")
			(hide yes)
			(effects
				(font
					(size 1.27 1.27)
				)
				(justify mirror)
			)
		)
		(property "Value" ""
			(at 0 0 0)
			(layer "B.Fab")
			(effects
				(font
					(size 1.27 1.27)
				)
				(justify mirror)
			)
		)
		(duplicate_pad_numbers_are_jumpers no)
		(fp_line
			(start -0.7874 -0.4064)
			(end -0.7874 0.4064)
			(stroke
				(width 0.1524)
				(type default)
			)
			(layer "B.SilkS")
		)
		(fp_line
			(start -0.7874 0.4064)
			(end 0.7874 0.4064)
			(stroke
				(width 0.1524)
				(type default)
			)
			(layer "B.SilkS")
		)
		(fp_line
			(start 0.7874 -0.4064)
			(end -0.7874 -0.4064)
			(stroke
				(width 0.1524)
				(type default)
			)
			(layer "B.SilkS")
		)
		(fp_line
			(start 0.7874 0.4064)
			(end 0.7874 -0.4064)
			(stroke
				(width 0.1524)
				(type default)
			)
			(layer "B.SilkS")
		)
		(fp_line
			(start -0.67945 -0.3048)
			(end -0.67945 0.3048)
			(stroke
				(width 0.1)
				(type default)
			)
			(layer "B.Fab")
		)
		(fp_line
			(start -0.67945 0.3048)
			(end -0.120396 0.3048)
			(stroke
				(width 0.1)
				(type default)
			)
			(layer "B.Fab")
		)
		(fp_line
			(start -0.12065 -0.3048)
			(end -0.67945 -0.3048)
			(stroke
				(width 0.1)
				(type default)
			)
			(layer "B.Fab")
		)
		(fp_line
			(start -0.12065 -0.2794)
			(end -0.12065 -0.3048)
			(stroke
				(width 0.1)
				(type default)
			)
			(layer "B.Fab")
		)
		(fp_line
			(start -0.120396 0.2794)
			(end 0.12065 0.2794)
			(stroke
				(width 0.1)
				(type default)
			)
			(layer "B.Fab")
		)
		(fp_line
			(start -0.120396 0.3048)
			(end -0.120396 0.2794)
			(stroke
				(width 0.1)
				(type default)
			)
			(layer "B.Fab")
		)
		(fp_line
			(start 0.12065 -0.305054)
			(end 0.12065 -0.2794)
			(stroke
				(width 0.1)
				(type default)
			)
			(layer "B.Fab")
		)
		(fp_line
			(start 0.12065 -0.2794)
			(end -0.12065 -0.2794)
			(stroke
				(width 0.1)
				(type default)
			)
			(layer "B.Fab")
		)
		(fp_line
			(start 0.12065 0.2794)
			(end 0.12065 0.3048)
			(stroke
				(width 0.1)
				(type default)
			)
			(layer "B.Fab")
		)
		(fp_line
			(start 0.12065 0.3048)
			(end 0.67945 0.3048)
			(stroke
				(width 0.1)
				(type default)
			)
			(layer "B.Fab")
		)
		(fp_line
			(start 0.67945 -0.305054)
			(end 0.12065 -0.305054)
			(stroke
				(width 0.1)
				(type default)
			)
			(layer "B.Fab")
		)
		(fp_line
			(start 0.67945 0.3048)
			(end 0.67945 -0.305054)
			(stroke
				(width 0.1)
				(type default)
			)
			(layer "B.Fab")
		)
		(pad "1" smd circle
			(at 0.40005 0 180)
			(size 0 0)
			(layers "B.Cu" "B.Mask" "B.Paste")
			(net "GND")
		)
		(pad "2" smd circle
			(at -0.40005 0 180)
			(size 0 0)
			(layers "B.Cu" "B.Mask" "B.Paste")
			(net "SPI_BIC1_CS0_LS01_N_DIR1")
		)
	)
	(footprint ""
		(layer "B.Cu")
		(at 342.493854 -226.387152)
		(property "Reference" "C2028"
			(at 0 0 0)
			(layer "B.SilkS")
			(hide yes)
			(effects
				(font
					(size 1.27 1.27)
				)
				(justify mirror)
			)
		)
		(property "Value" ""
			(at 0 0 0)
			(layer "B.Fab")
			(effects
				(font
					(size 1.27 1.27)
				)
				(justify mirror)
			)
		)
		(duplicate_pad_numbers_are_jumpers no)
		(fp_line
			(start -0.69215 -0.2921)
			(end -0.69215 0.2921)
			(stroke
				(width 0.1524)
				(type default)
			)
			(layer "B.SilkS")
		)
		(fp_line
			(start -0.69215 0.2921)
			(end 0.69215 0.2921)
			(stroke
				(width 0.1524)
				(type default)
			)
			(layer "B.SilkS")
		)
		(fp_line
			(start 0.69215 -0.2921)
			(end -0.69215 -0.2921)
			(stroke
				(width 0.1524)
				(type default)
			)
			(layer "B.SilkS")
		)
		(fp_line
			(start 0.69215 0.2921)
			(end 0.69215 -0.2921)
			(stroke
				(width 0.1524)
				(type default)
			)
			(layer "B.SilkS")
		)
		(fp_line
			(start -0.51435 -0.2794)
			(end -0.51435 0.2794)
			(stroke
				(width 0.1)
				(type default)
			)
			(layer "B.Fab")
		)
		(fp_line
			(start -0.51435 0.2794)
			(end 0.51435 0.2794)
			(stroke
				(width 0.1)
				(type default)
			)
			(layer "B.Fab")
		)
		(fp_line
			(start 0.51435 -0.2794)
			(end -0.51435 -0.2794)
			(stroke
				(width 0.1)
				(type default)
			)
			(layer "B.Fab")
		)
		(fp_line
			(start 0.51435 0.2794)
			(end 0.51435 -0.2794)
			(stroke
				(width 0.1)
				(type default)
			)
			(layer "B.Fab")
		)
		(pad "1" smd circle
			(at 0.40005 0 180)
			(size 0 0)
			(layers "B.Cu" "B.Mask" "B.Paste")
			(net "P3V3_FPGA_VCCIO0")
		)
		(pad "2" smd circle
			(at -0.40005 0 180)
			(size 0 0)
			(layers "B.Cu" "B.Mask" "B.Paste")
			(net "GND")
		)
		(zone
			(layer "B.Cu")
			(hatch none 0.5)
			(connect_pads
				(clearance 0)
			)
			(min_thickness 0.25)
			(keepout
				(tracks not_allowed)
				(vias allowed)
				(pads allowed)
				(copperpour not_allowed)
				(footprints allowed)
			)
			(placement
				(enabled no)
				(sheetname "")
			)
			(fill
				(thermal_gap 0.5)
				(thermal_bridge_width 0.5)
				(island_removal_mode 0)
			)
			(polygon
				(pts
					(xy 342.684354 -226.299522) (xy 342.592914 -226.241356) (xy 342.393524 -226.241356) (xy 342.303354 -226.299522)
					(xy 342.303354 -226.474782) (xy 342.393524 -226.533202) (xy 342.592914 -226.533202) (xy 342.684354 -226.475036)
				)
			)
		)
	)
	(footprint ""
		(layer "B.Cu")
		(at 413.174942 -286.399732 90)
		(property "Reference" "C3504"
			(at 0 0 90)
			(layer "B.SilkS")
			(hide yes)
			(effects
				(font
					(size 1.27 1.27)
				)
				(justify mirror)
			)
		)
		(property "Value" ""
			(at 0 0 90)
			(layer "B.Fab")
			(effects
				(font
					(size 1.27 1.27)
				)
				(justify mirror)
			)
		)
		(duplicate_pad_numbers_are_jumpers no)
		(fp_line
			(start 0.299974 -0.150114)
			(end -0.299974 -0.150114)
			(stroke
				(width 0.1)
				(type default)
			)
			(layer "B.Fab")
		)
		(fp_line
			(start -0.299974 -0.150114)
			(end -0.299974 0.150114)
			(stroke
				(width 0.1)
				(type default)
			)
			(layer "B.Fab")
		)
		(fp_line
			(start 0.299974 0.150114)
			(end 0.299974 -0.150114)
			(stroke
				(width 0.1)
				(type default)
			)
			(layer "B.Fab")
		)
		(fp_line
			(start -0.299974 0.150114)
			(end 0.299974 0.150114)
			(stroke
				(width 0.1)
				(type default)
			)
			(layer "B.Fab")
		)
		(pad "1" smd rect
			(at 0.2667 0 270)
			(size 0.3048 0.381)
			(layers "B.Cu" "B.Mask" "B.Paste")
			(net "P1V25_SERDES_VDDPLL_PEX3")
		)
		(pad "2" smd rect
			(at -0.2667 0 270)
			(size 0.3048 0.381)
			(layers "B.Cu" "B.Mask" "B.Paste")
			(net "GND")
		)
	)
	(footprint ""
		(layer "B.Cu")
		(at 168.150032 -299.699934 -90)
		(property "Reference" "C1432"
			(at 0 0 90)
			(layer "B.SilkS")
			(hide yes)
			(effects
				(font
					(size 1.27 1.27)
				)
				(justify mirror)
			)
		)
		(property "Value" ""
			(at 0 0 90)
			(layer "B.Fab")
			(effects
				(font
					(size 1.27 1.27)
				)
				(justify mirror)
			)
		)
		(duplicate_pad_numbers_are_jumpers no)
		(fp_line
			(start -0.299974 0.150114)
			(end 0.299974 0.150114)
			(stroke
				(width 0.1)
				(type default)
			)
			(layer "B.Fab")
		)
		(fp_line
			(start 0.299974 0.150114)
			(end 0.299974 -0.150114)
			(stroke
				(width 0.1)
				(type default)
			)
			(layer "B.Fab")
		)
		(fp_line
			(start -0.299974 -0.150114)
			(end -0.299974 0.150114)
			(stroke
				(width 0.1)
				(type default)
			)
			(layer "B.Fab")
		)
		(fp_line
			(start 0.299974 -0.150114)
			(end -0.299974 -0.150114)
			(stroke
				(width 0.1)
				(type default)
			)
			(layer "B.Fab")
		)
		(pad "1" smd rect
			(at 0.2667 0 90)
			(size 0.3048 0.381)
			(layers "B.Cu" "B.Mask" "B.Paste")
			(net "P0V8_SERDES_VDDA_PEX1")
		)
		(pad "2" smd rect
			(at -0.2667 0 90)
			(size 0.3048 0.381)
			(layers "B.Cu" "B.Mask" "B.Paste")
			(net "GND")
		)
	)
)
